(kicad_pcb
	(version 20260206)
	(generator "pcbnew")
	(generator_version "10.0")
	(general
		(thickness 1.6)
		(legacy_teardrops no)
	)
	(paper "A4")
	(title_block
		(title "01162023_DA0F0TEBIF0_F0T_Expander_BD_F_brd_V02_OCP.brd")
		(comment 1 "Grand Teton / footprints 7943-7953 of 9728")
	)
	(layers
		(0 "F.Cu" signal "TOP")
		(4 "In1.Cu" signal "GND")
		(6 "In2.Cu" signal "VCC")
		(8 "In3.Cu" signal "VCC1")
		(10 "In4.Cu" signal "GND1")
		(12 "In5.Cu" signal "IN1")
		(14 "In6.Cu" signal "GND2")
		(16 "In7.Cu" signal "IN2")
		(18 "In8.Cu" signal "GND3")
		(20 "In9.Cu" signal "IN3")
		(22 "In10.Cu" signal "GND4")
		(24 "In11.Cu" signal "IN4")
		(26 "In12.Cu" signal "GND5")
		(28 "In13.Cu" signal "IN5")
		(30 "In14.Cu" signal "GND6")
		(32 "In15.Cu" signal "IN6")
		(34 "In16.Cu" signal "GND7")
		(2 "B.Cu" signal "BOTTOM")
		(9 "F.Adhes" user "F.Adhesive")
		(11 "B.Adhes" user "B.Adhesive")
		(13 "F.Paste" user "Package Geometry/Pastemask Top")
		(15 "B.Paste" user "Package Geometry/Pastemask Bottom")
		(5 "F.SilkS" user "Ref Des/Silkscreen Top")
		(7 "B.SilkS" user "Ref Des/Silkscreen Bottom")
		(1 "F.Mask" user "Board Geometry/Soldermask Top")
		(3 "B.Mask" user "Board Geometry/Soldermask Bottom")
		(17 "Dwgs.User" user "User.Drawings")
		(19 "Cmts.User" user "User.Comments")
		(21 "Eco1.User" user "User.Eco1")
		(23 "Eco2.User" user "User.Eco2")
		(25 "Edge.Cuts" user "Board Geometry/Outline")
		(27 "Margin" user)
		(31 "F.CrtYd" user "Package Geometry/Place Bound Top")
		(29 "B.CrtYd" user "Package Geometry/Place Bound Bottom")
		(35 "F.Fab" user "Ref Des/Assembly Top")
		(33 "B.Fab" user "Ref Des/Assembly Bottom")
	)
	(footprint ""
		(layer "B.Cu")
		(at 159.523684 -286.018732)
		(property "Reference" "C3161"
			(at 0 0 0)
			(layer "B.SilkS")
			(hide yes)
			(effects
				(font
					(size 1.27 1.27)
				)
				(justify mirror)
			)
		)
		(property "Value" ""
			(at 0 0 0)
			(layer "B.Fab")
			(effects
				(font
					(size 1.27 1.27)
				)
				(justify mirror)
			)
		)
		(duplicate_pad_numbers_are_jumpers no)
		(fp_line
			(start -1.2954 -0.5842)
			(end -1.2954 0.5842)
			(stroke
				(width 0.1524)
				(type default)
			)
			(layer "B.SilkS")
		)
		(fp_line
			(start -1.2954 0.5842)
			(end 1.2954 0.5842)
			(stroke
				(width 0.1524)
				(type default)
			)
			(layer "B.SilkS")
		)
		(fp_line
			(start 1.2954 -0.5842)
			(end -1.2954 -0.5842)
			(stroke
				(width 0.1524)
				(type default)
			)
			(layer "B.SilkS")
		)
		(fp_line
			(start 1.2954 0.5842)
			(end 1.2954 -0.5842)
			(stroke
				(width 0.1524)
				(type default)
			)
			(layer "B.SilkS")
		)
		(fp_line
			(start -1.1938 -0.4064)
			(end -1.1938 0.4064)
			(stroke
				(width 0.1)
				(type default)
			)
			(layer "B.Fab")
		)
		(fp_line
			(start -1.1938 0.4064)
			(end -0.8636 0.4064)
			(stroke
				(width 0.1)
				(type default)
			)
			(layer "B.Fab")
		)
		(fp_line
			(start -0.8636 -0.4572)
			(end -0.8636 -0.4064)
			(stroke
				(width 0.1)
				(type default)
			)
			(layer "B.Fab")
		)
		(fp_line
			(start -0.8636 -0.4064)
			(end -1.1938 -0.4064)
			(stroke
				(width 0.1)
				(type default)
			)
			(layer "B.Fab")
		)
		(fp_line
			(start -0.8636 0.4064)
			(end -0.8636 0.4572)
			(stroke
				(width 0.1)
				(type default)
			)
			(layer "B.Fab")
		)
		(fp_line
			(start -0.8636 0.4572)
			(end 0.8636 0.4572)
			(stroke
				(width 0.1)
				(type default)
			)
			(layer "B.Fab")
		)
		(fp_line
			(start 0.8636 -0.4572)
			(end -0.8636 -0.4572)
			(stroke
				(width 0.1)
				(type default)
			)
			(layer "B.Fab")
		)
		(fp_line
			(start 0.8636 -0.4064)
			(end 0.8636 -0.4572)
			(stroke
				(width 0.1)
				(type default)
			)
			(layer "B.Fab")
		)
		(fp_line
			(start 0.8636 0.4064)
			(end 1.1938 0.4064)
			(stroke
				(width 0.1)
				(type default)
			)
			(layer "B.Fab")
		)
		(fp_line
			(start 0.8636 0.4572)
			(end 0.8636 0.4064)
			(stroke
				(width 0.1)
				(type default)
			)
			(layer "B.Fab")
		)
		(fp_line
			(start 1.1938 -0.4064)
			(end 0.8636 -0.4064)
			(stroke
				(width 0.1)
				(type default)
			)
			(layer "B.Fab")
		)
		(fp_line
			(start 1.1938 0.4064)
			(end 1.1938 -0.4064)
			(stroke
				(width 0.1)
				(type default)
			)
			(layer "B.Fab")
		)
		(pad "1" smd rect
			(at 0.7366 0 270)
			(size 0.7112 0.8128)
			(layers "B.Cu" "B.Mask" "B.Paste")
			(net "P1V8_PEX")
		)
		(pad "2" smd rect
			(at -0.7366 0 270)
			(size 0.7112 0.8128)
			(layers "B.Cu" "B.Mask" "B.Paste")
			(net "GND")
		)
	)
	(footprint ""
		(layer "B.Cu")
		(at 292.79977 -301.599854 -90)
		(property "Reference" "C1716"
			(at 0 0 90)
			(layer "B.SilkS")
			(hide yes)
			(effects
				(font
					(size 1.27 1.27)
				)
				(justify mirror)
			)
		)
		(property "Value" ""
			(at 0 0 90)
			(layer "B.Fab")
			(effects
				(font
					(size 1.27 1.27)
				)
				(justify mirror)
			)
		)
		(duplicate_pad_numbers_are_jumpers no)
		(fp_line
			(start -0.299974 0.150114)
			(end 0.299974 0.150114)
			(stroke
				(width 0.1)
				(type default)
			)
			(layer "B.Fab")
		)
		(fp_line
			(start 0.299974 0.150114)
			(end 0.299974 -0.150114)
			(stroke
				(width 0.1)
				(type default)
			)
			(layer "B.Fab")
		)
		(fp_line
			(start -0.299974 -0.150114)
			(end -0.299974 0.150114)
			(stroke
				(width 0.1)
				(type default)
			)
			(layer "B.Fab")
		)
		(fp_line
			(start 0.299974 -0.150114)
			(end -0.299974 -0.150114)
			(stroke
				(width 0.1)
				(type default)
			)
			(layer "B.Fab")
		)
		(pad "1" smd rect
			(at 0.2667 0 90)
			(size 0.3048 0.381)
			(layers "B.Cu" "B.Mask" "B.Paste")
			(net "P0V8_SERDES_VDDA_PEX2")
		)
		(pad "2" smd rect
			(at -0.2667 0 90)
			(size 0.3048 0.381)
			(layers "B.Cu" "B.Mask" "B.Paste")
			(net "GND")
		)
	)
	(footprint ""
		(layer "B.Cu")
		(at 100.90023 -323.111622 180)
		(property "Reference" "PJ18"
			(at 0 0 0)
			(layer "B.SilkS")
			(hide yes)
			(effects
				(font
					(size 1.27 1.27)
				)
				(justify mirror)
			)
		)
		(property "Value" ""
			(at 0 0 0)
			(layer "B.Fab")
			(effects
				(font
					(size 1.27 1.27)
				)
				(justify mirror)
			)
		)
		(duplicate_pad_numbers_are_jumpers no)
		(pad "1" smd circle
			(at 0.40005 0 270)
			(size 0 0)
			(layers "B.Cu" "B.Mask" "B.Paste")
			(net "VSENSE_P0V8_PEX0_SKT_VSEN")
		)
		(pad "2" smd rect
			(at -0.40005 0 180)
			(size 0.4572 0.508)
			(layers "B.Cu" "B.Mask" "B.Paste")
			(net "SH_P0V8_PEX0_VSEN0_L")
		)
		(zone
			(layer "B.Cu")
			(hatch none 0.5)
			(connect_pads
				(clearance 0)
			)
			(min_thickness 0.25)
			(keepout
				(tracks allowed)
				(vias not_allowed)
				(pads allowed)
				(copperpour not_allowed)
				(footprints allowed)
			)
			(placement
				(enabled no)
				(sheetname "")
			)
			(fill
				(thermal_gap 0.5)
				(thermal_bridge_width 0.5)
				(island_removal_mode 0)
			)
			(polygon
				(pts
					(xy 101.58603 -323.416422) (xy 101.58603 -322.806822) (xy 100.21443 -322.806822) (xy 100.21443 -323.416422)
				)
			)
		)
	)
	(footprint ""
		(layer "B.Cu")
		(at 68.941442 -287.824926)
		(property "Reference" "C2997"
			(at 0 0 0)
			(layer "B.SilkS")
			(hide yes)
			(effects
				(font
					(size 1.27 1.27)
				)
				(justify mirror)
			)
		)
		(property "Value" ""
			(at 0 0 0)
			(layer "B.Fab")
			(effects
				(font
					(size 1.27 1.27)
				)
				(justify mirror)
			)
		)
		(duplicate_pad_numbers_are_jumpers no)
		(fp_line
			(start -0.299974 -0.150114)
			(end -0.299974 0.150114)
			(stroke
				(width 0.1)
				(type default)
			)
			(layer "B.Fab")
		)
		(fp_line
			(start -0.299974 0.150114)
			(end 0.299974 0.150114)
			(stroke
				(width 0.1)
				(type default)
			)
			(layer "B.Fab")
		)
		(fp_line
			(start 0.299974 -0.150114)
			(end -0.299974 -0.150114)
			(stroke
				(width 0.1)
				(type default)
			)
			(layer "B.Fab")
		)
		(fp_line
			(start 0.299974 0.150114)
			(end 0.299974 -0.150114)
			(stroke
				(width 0.1)
				(type default)
			)
			(layer "B.Fab")
		)
		(pad "1" smd rect
			(at 0.2667 0 180)
			(size 0.3048 0.381)
			(layers "B.Cu" "B.Mask" "B.Paste")
			(net "P1V8_VDDA_PEX0")
		)
		(pad "2" smd rect
			(at -0.2667 0 180)
			(size 0.3048 0.381)
			(layers "B.Cu" "B.Mask" "B.Paste")
			(net "GND")
		)
	)
	(footprint ""
		(layer "B.Cu")
		(at 46.355 -295.2623)
		(property "Reference" "C3043"
			(at 0 0 0)
			(layer "B.SilkS")
			(hide yes)
			(effects
				(font
					(size 1.27 1.27)
				)
				(justify mirror)
			)
		)
		(property "Value" ""
			(at 0 0 0)
			(layer "B.Fab")
			(effects
				(font
					(size 1.27 1.27)
				)
				(justify mirror)
			)
		)
		(duplicate_pad_numbers_are_jumpers no)
		(fp_line
			(start -0.299974 -0.150114)
			(end -0.299974 0.150114)
			(stroke
				(width 0.1)
				(type default)
			)
			(layer "B.Fab")
		)
		(fp_line
			(start -0.299974 0.150114)
			(end 0.299974 0.150114)
			(stroke
				(width 0.1)
				(type default)
			)
			(layer "B.Fab")
		)
		(fp_line
			(start 0.299974 -0.150114)
			(end -0.299974 -0.150114)
			(stroke
				(width 0.1)
				(type default)
			)
			(layer "B.Fab")
		)
		(fp_line
			(start 0.299974 0.150114)
			(end 0.299974 -0.150114)
			(stroke
				(width 0.1)
				(type default)
			)
			(layer "B.Fab")
		)
		(pad "1" smd rect
			(at 0.2667 0 180)
			(size 0.3048 0.381)
			(layers "B.Cu" "B.Mask" "B.Paste")
			(net "PCEPLL4_VDDA18_PEX0")
		)
		(pad "2" smd rect
			(at -0.2667 0 180)
			(size 0.3048 0.381)
			(layers "B.Cu" "B.Mask" "B.Paste")
			(net "GND")
		)
	)
	(footprint ""
		(layer "B.Cu")
		(at 160.549844 -297.815)
		(property "Reference" "C3181"
			(at 0 0 0)
			(layer "B.SilkS")
			(hide yes)
			(effects
				(font
					(size 1.27 1.27)
				)
				(justify mirror)
			)
		)
		(property "Value" ""
			(at 0 0 0)
			(layer "B.Fab")
			(effects
				(font
					(size 1.27 1.27)
				)
				(justify mirror)
			)
		)
		(duplicate_pad_numbers_are_jumpers no)
		(fp_line
			(start -0.299974 -0.150114)
			(end -0.299974 0.150114)
			(stroke
				(width 0.1)
				(type default)
			)
			(layer "B.Fab")
		)
		(fp_line
			(start -0.299974 0.150114)
			(end 0.299974 0.150114)
			(stroke
				(width 0.1)
				(type default)
			)
			(layer "B.Fab")
		)
		(fp_line
			(start 0.299974 -0.150114)
			(end -0.299974 -0.150114)
			(stroke
				(width 0.1)
				(type default)
			)
			(layer "B.Fab")
		)
		(fp_line
			(start 0.299974 0.150114)
			(end 0.299974 -0.150114)
			(stroke
				(width 0.1)
				(type default)
			)
			(layer "B.Fab")
		)
		(pad "1" smd rect
			(at 0.2667 0 180)
			(size 0.3048 0.381)
			(layers "B.Cu" "B.Mask" "B.Paste")
			(net "P1V8_VDDA_PEX1")
		)
		(pad "2" smd rect
			(at -0.2667 0 180)
			(size 0.3048 0.381)
			(layers "B.Cu" "B.Mask" "B.Paste")
			(net "GND")
		)
	)
	(footprint ""
		(layer "B.Cu")
		(at 234.993434 -352.307906 180)
		(property "Reference" "PR7156"
			(at 0 0 0)
			(layer "B.SilkS")
			(hide yes)
			(effects
				(font
					(size 1.27 1.27)
				)
				(justify mirror)
			)
		)
		(property "Value" ""
			(at 0 0 0)
			(layer "B.Fab")
			(effects
				(font
					(size 1.27 1.27)
				)
				(justify mirror)
			)
		)
		(duplicate_pad_numbers_are_jumpers no)
		(fp_line
			(start 0.7874 0.4064)
			(end 0.7874 -0.4064)
			(stroke
				(width 0.1524)
				(type default)
			)
			(layer "B.SilkS")
		)
		(fp_line
			(start 0.7874 -0.4064)
			(end -0.7874 -0.4064)
			(stroke
				(width 0.1524)
				(type default)
			)
			(layer "B.SilkS")
		)
		(fp_line
			(start -0.7874 0.4064)
			(end 0.7874 0.4064)
			(stroke
				(width 0.1524)
				(type default)
			)
			(layer "B.SilkS")
		)
		(fp_line
			(start -0.7874 -0.4064)
			(end -0.7874 0.4064)
			(stroke
				(width 0.1524)
				(type default)
			)
			(layer "B.SilkS")
		)
		(fp_line
			(start 0.67945 0.3048)
			(end 0.67945 -0.305054)
			(stroke
				(width 0.1)
				(type default)
			)
			(layer "B.Fab")
		)
		(fp_line
			(start 0.67945 -0.305054)
			(end 0.12065 -0.305054)
			(stroke
				(width 0.1)
				(type default)
			)
			(layer "B.Fab")
		)
		(fp_line
			(start 0.12065 0.3048)
			(end 0.67945 0.3048)
			(stroke
				(width 0.1)
				(type default)
			)
			(layer "B.Fab")
		)
		(fp_line
			(start 0.12065 0.2794)
			(end 0.12065 0.3048)
			(stroke
				(width 0.1)
				(type default)
			)
			(layer "B.Fab")
		)
		(fp_line
			(start 0.12065 -0.2794)
			(end -0.12065 -0.2794)
			(stroke
				(width 0.1)
				(type default)
			)
			(layer "B.Fab")
		)
		(fp_line
			(start 0.12065 -0.305054)
			(end 0.12065 -0.2794)
			(stroke
				(width 0.1)
				(type default)
			)
			(layer "B.Fab")
		)
		(fp_line
			(start -0.120396 0.3048)
			(end -0.120396 0.2794)
			(stroke
				(width 0.1)
				(type default)
			)
			(layer "B.Fab")
		)
		(fp_line
			(start -0.120396 0.2794)
			(end 0.12065 0.2794)
			(stroke
				(width 0.1)
				(type default)
			)
			(layer "B.Fab")
		)
		(fp_line
			(start -0.12065 -0.2794)
			(end -0.12065 -0.3048)
			(stroke
				(width 0.1)
				(type default)
			)
			(layer "B.Fab")
		)
		(fp_line
			(start -0.12065 -0.3048)
			(end -0.67945 -0.3048)
			(stroke
				(width 0.1)
				(type default)
			)
			(layer "B.Fab")
		)
		(fp_line
			(start -0.67945 0.3048)
			(end -0.120396 0.3048)
			(stroke
				(width 0.1)
				(type default)
			)
			(layer "B.Fab")
		)
		(fp_line
			(start -0.67945 -0.3048)
			(end -0.67945 0.3048)
			(stroke
				(width 0.1)
				(type default)
			)
			(layer "B.Fab")
		)
		(pad "1" smd circle
			(at 0.40005 0)
			(size 0 0)
			(layers "B.Cu" "B.Mask" "B.Paste")
			(net "P12V_HSC_SENSE2_N")
		)
		(pad "2" smd circle
			(at -0.40005 0)
			(size 0 0)
			(layers "B.Cu" "B.Mask" "B.Paste")
			(net "P12V_HSC_SENSE2_R1_N")
		)
	)
	(footprint ""
		(layer "B.Cu")
		(at 342.493854 -213.587076 180)
		(property "Reference" "C2051"
			(at 0 0 0)
			(layer "B.SilkS")
			(hide yes)
			(effects
				(font
					(size 1.27 1.27)
				)
				(justify mirror)
			)
		)
		(property "Value" ""
			(at 0 0 0)
			(layer "B.Fab")
			(effects
				(font
					(size 1.27 1.27)
				)
				(justify mirror)
			)
		)
		(duplicate_pad_numbers_are_jumpers no)
		(fp_line
			(start 0.69215 0.2921)
			(end 0.69215 -0.2921)
			(stroke
				(width 0.1524)
				(type default)
			)
			(layer "B.SilkS")
		)
		(fp_line
			(start 0.69215 -0.2921)
			(end -0.69215 -0.2921)
			(stroke
				(width 0.1524)
				(type default)
			)
			(layer "B.SilkS")
		)
		(fp_line
			(start -0.69215 0.2921)
			(end 0.69215 0.2921)
			(stroke
				(width 0.1524)
				(type default)
			)
			(layer "B.SilkS")
		)
		(fp_line
			(start -0.69215 -0.2921)
			(end -0.69215 0.2921)
			(stroke
				(width 0.1524)
				(type default)
			)
			(layer "B.SilkS")
		)
		(fp_line
			(start 0.51435 0.2794)
			(end 0.51435 -0.2794)
			(stroke
				(width 0.1)
				(type default)
			)
			(layer "B.Fab")
		)
		(fp_line
			(start 0.51435 -0.2794)
			(end -0.51435 -0.2794)
			(stroke
				(width 0.1)
				(type default)
			)
			(layer "B.Fab")
		)
		(fp_line
			(start -0.51435 0.2794)
			(end 0.51435 0.2794)
			(stroke
				(width 0.1)
				(type default)
			)
			(layer "B.Fab")
		)
		(fp_line
			(start -0.51435 -0.2794)
			(end -0.51435 0.2794)
			(stroke
				(width 0.1)
				(type default)
			)
			(layer "B.Fab")
		)
		(pad "1" smd circle
			(at 0.40005 0)
			(size 0 0)
			(layers "B.Cu" "B.Mask" "B.Paste")
			(net "P3V3_FPGA_VCCIO2")
		)
		(pad "2" smd circle
			(at -0.40005 0)
			(size 0 0)
			(layers "B.Cu" "B.Mask" "B.Paste")
			(net "GND")
		)
		(zone
			(layer "B.Cu")
			(hatch none 0.5)
			(connect_pads
				(clearance 0)
			)
			(min_thickness 0.25)
			(keepout
				(tracks not_allowed)
				(vias allowed)
				(pads allowed)
				(copperpour not_allowed)
				(footprints allowed)
			)
			(placement
				(enabled no)
				(sheetname "")
			)
			(fill
				(thermal_gap 0.5)
				(thermal_bridge_width 0.5)
				(island_removal_mode 0)
			)
			(polygon
				(pts
					(xy 342.303354 -213.674706) (xy 342.394794 -213.732872) (xy 342.594184 -213.732872) (xy 342.684354 -213.674706)
					(xy 342.684354 -213.499446) (xy 342.594184 -213.441026) (xy 342.394794 -213.441026) (xy 342.303354 -213.499192)
				)
			)
		)
	)
	(footprint ""
		(layer "B.Cu")
		(at 415.074862 -297.79976 -90)
		(property "Reference" "C1948"
			(at 0 0 90)
			(layer "B.SilkS")
			(hide yes)
			(effects
				(font
					(size 1.27 1.27)
				)
				(justify mirror)
			)
		)
		(property "Value" ""
			(at 0 0 90)
			(layer "B.Fab")
			(effects
				(font
					(size 1.27 1.27)
				)
				(justify mirror)
			)
		)
		(duplicate_pad_numbers_are_jumpers no)
		(fp_line
			(start -0.299974 0.150114)
			(end 0.299974 0.150114)
			(stroke
				(width 0.1)
				(type default)
			)
			(layer "B.Fab")
		)
		(fp_line
			(start 0.299974 0.150114)
			(end 0.299974 -0.150114)
			(stroke
				(width 0.1)
				(type default)
			)
			(layer "B.Fab")
		)
		(fp_line
			(start -0.299974 -0.150114)
			(end -0.299974 0.150114)
			(stroke
				(width 0.1)
				(type default)
			)
			(layer "B.Fab")
		)
		(fp_line
			(start 0.299974 -0.150114)
			(end -0.299974 -0.150114)
			(stroke
				(width 0.1)
				(type default)
			)
			(layer "B.Fab")
		)
		(pad "1" smd rect
			(at 0.2667 0 90)
			(size 0.3048 0.381)
			(layers "B.Cu" "B.Mask" "B.Paste")
			(net "P0V8_SERDES_VDDA_PEX3")
		)
		(pad "2" smd rect
			(at -0.2667 0 90)
			(size 0.3048 0.381)
			(layers "B.Cu" "B.Mask" "B.Paste")
			(net "GND")
		)
	)
	(footprint ""
		(layer "B.Cu")
		(at 449.810378 -273.486118)
		(property "Reference" "C4404"
			(at 0 0 0)
			(layer "B.SilkS")
			(hide yes)
			(effects
				(font
					(size 1.27 1.27)
				)
				(justify mirror)
			)
		)
		(property "Value" ""
			(at 0 0 0)
			(layer "B.Fab")
			(effects
				(font
					(size 1.27 1.27)
				)
				(justify mirror)
			)
		)
		(duplicate_pad_numbers_are_jumpers no)
		(fp_line
			(start -0.299974 -0.150114)
			(end -0.299974 0.150114)
			(stroke
				(width 0.1)
				(type default)
			)
			(layer "B.Fab")
		)
		(fp_line
			(start -0.299974 0.150114)
			(end 0.299974 0.150114)
			(stroke
				(width 0.1)
				(type default)
			)
			(layer "B.Fab")
		)
		(fp_line
			(start 0.299974 -0.150114)
			(end -0.299974 -0.150114)
			(stroke
				(width 0.1)
				(type default)
			)
			(layer "B.Fab")
		)
		(fp_line
			(start 0.299974 0.150114)
			(end 0.299974 -0.150114)
			(stroke
				(width 0.1)
				(type default)
			)
			(layer "B.Fab")
		)
		(pad "1" smd rect
			(at 0.2667 0 180)
			(size 0.3048 0.381)
			(layers "B.Cu" "B.Mask" "B.Paste")
			(net "P1V25_PEX3")
		)
		(pad "2" smd rect
			(at -0.2667 0 180)
			(size 0.3048 0.381)
			(layers "B.Cu" "B.Mask" "B.Paste")
			(net "GND")
		)
	)
	(footprint ""
		(layer "B.Cu")
		(at 182.39994 -303.499774 -90)
		(property "Reference" "C3086"
			(at 0 0 90)
			(layer "B.SilkS")
			(hide yes)
			(effects
				(font
					(size 1.27 1.27)
				)
				(justify mirror)
			)
		)
		(property "Value" ""
			(at 0 0 90)
			(layer "B.Fab")
			(effects
				(font
					(size 1.27 1.27)
				)
				(justify mirror)
			)
		)
		(duplicate_pad_numbers_are_jumpers no)
		(fp_line
			(start -0.299974 0.150114)
			(end 0.299974 0.150114)
			(stroke
				(width 0.1)
				(type default)
			)
			(layer "B.Fab")
		)
		(fp_line
			(start 0.299974 0.150114)
			(end 0.299974 -0.150114)
			(stroke
				(width 0.1)
				(type default)
			)
			(layer "B.Fab")
		)
		(fp_line
			(start -0.299974 -0.150114)
			(end -0.299974 0.150114)
			(stroke
				(width 0.1)
				(type default)
			)
			(layer "B.Fab")
		)
		(fp_line
			(start 0.299974 -0.150114)
			(end -0.299974 -0.150114)
			(stroke
				(width 0.1)
				(type default)
			)
			(layer "B.Fab")
		)
		(pad "1" smd rect
			(at 0.2667 0 90)
			(size 0.3048 0.381)
			(layers "B.Cu" "B.Mask" "B.Paste")
			(net "P1V25_PEX1")
		)
		(pad "2" smd rect
			(at -0.2667 0 90)
			(size 0.3048 0.381)
			(layers "B.Cu" "B.Mask" "B.Paste")
			(net "GND")
		)
	)
)
